(kicad_pcb
	(version 20260206)
	(generator "pcbnew")
	(generator_version "10.0")
	(general
		(thickness 1.6)
		(legacy_teardrops no)
	)
	(paper "A4")
	(title_block
		(title "Bryce Canyon_SCC_16316-1_OCP.brd")
		(comment 1 "Bryce Canyon / footprints 265-271 of 1561")
	)
	(layers
		(0 "F.Cu" signal "TOP")
		(4 "In1.Cu" signal "L2GND")
		(6 "In2.Cu" signal "L3")
		(8 "In3.Cu" signal "L4VCC")
		(10 "In4.Cu" signal "L5VCC")
		(12 "In5.Cu" signal "L6")
		(14 "In6.Cu" signal "L7GND")
		(2 "B.Cu" signal "BOTTOM")
		(9 "F.Adhes" user "F.Adhesive")
		(11 "B.Adhes" user "B.Adhesive")
		(13 "F.Paste" user "Package Geometry/Pastemask Top")
		(15 "B.Paste" user "Package Geometry/Pastemask Bottom")
		(5 "F.SilkS" user "Ref Des/Silkscreen Top")
		(7 "B.SilkS" user "Ref Des/Silkscreen Bottom")
		(1 "F.Mask" user "Board Geometry/Soldermask Top")
		(3 "B.Mask" user "Board Geometry/Soldermask Bottom")
		(17 "Dwgs.User" user "User.Drawings")
		(19 "Cmts.User" user "User.Comments")
		(21 "Eco1.User" user "User.Eco1")
		(23 "Eco2.User" user "User.Eco2")
		(25 "Edge.Cuts" user "Board Geometry/Outline")
		(27 "Margin" user)
		(31 "F.CrtYd" user "Package Geometry/Place Bound Top")
		(29 "B.CrtYd" user "Package Geometry/Place Bound Bottom")
		(35 "F.Fab" user "Ref Des/Assembly Top")
		(33 "B.Fab" user "Ref Des/Assembly Bottom")
	)
	(footprint ""
		(layer "F.Cu")
		(at 202.30338 -78.00848 -90)
		(property "Reference" "R366"
			(at 0 0 270)
			(layer "F.SilkS")
			(hide yes)
			(effects
				(font
					(size 1.27 1.27)
				)
			)
		)
		(property "Value" "0R2J-2-GP"
			(at 0.064008 -3.993896 270)
			(unlocked yes)
			(layer "F.Fab")
			(hide yes)
			(effects
				(font
					(size 1.016 1.016)
					(thickness 0.1524)
				)
			)
		)
		(property "Device Type" "R402H16"
			(at 0.064008 -5.517896 270)
			(unlocked yes)
			(layer "F.Fab")
			(hide yes)
			(effects
				(font
					(size 1.016 1.016)
					(thickness 0.1524)
				)
			)
		)
		(duplicate_pad_numbers_are_jumpers no)
		(fp_line
			(start -0.508 -0.9398)
			(end -0.508 0.9398)
			(stroke
				(width 0.1524)
				(type default)
			)
			(layer "F.SilkS")
		)
		(fp_line
			(start 0.508 -0.9398)
			(end -0.508 -0.9398)
			(stroke
				(width 0.1524)
				(type default)
			)
			(layer "F.SilkS")
		)
		(fp_rect
			(start -0.508 0.9398)
			(end 0.508 -0.9398)
			(stroke
				(width 0)
				(type default)
			)
			(fill no)
			(layer "F.CrtYd")
		)
		(fp_rect
			(start -0.508 0.9398)
			(end 0.508 -0.9398)
			(stroke
				(width 0)
				(type default)
			)
			(fill no)
			(layer "F.Fab")
		)
		(pad "1" smd custom
			(at 0 -0.4445 270)
			(size 0.1397 0.1397)
			(layers "F.Cu" "F.Mask" "F.Paste")
			(net "I2C_SCC_SCL2")
			(options
				(clearance outline)
				(anchor circle)
			)
			(primitives
				(gr_poly
					(pts
						(arc
							(start -0.1778 -0.2794)
							(mid -0.249642 -0.249642)
							(end -0.2794 -0.1778)
						)
						(arc
							(start -0.2794 0.1778)
							(mid -0.249642 0.249642)
							(end -0.1778 0.2794)
						)
						(arc
							(start 0.1778 0.2794)
							(mid 0.249642 0.249642)
							(end 0.2794 0.1778)
						)
						(arc
							(start 0.2794 -0.1778)
							(mid 0.249642 -0.249642)
							(end 0.1778 -0.2794)
						)
					)
					(width 0)
					(fill yes)
				)
			)
		)
		(pad "2" smd custom
			(at 0 0.4445 270)
			(size 0.1397 0.1397)
			(layers "F.Cu" "F.Mask" "F.Paste")
			(net "TEMP2_SCL")
			(options
				(clearance outline)
				(anchor circle)
			)
			(primitives
				(gr_poly
					(pts
						(arc
							(start -0.1778 -0.2794)
							(mid -0.249642 -0.249642)
							(end -0.2794 -0.1778)
						)
						(arc
							(start -0.2794 0.1778)
							(mid -0.249642 0.249642)
							(end -0.1778 0.2794)
						)
						(arc
							(start 0.1778 0.2794)
							(mid 0.249642 0.249642)
							(end 0.2794 0.1778)
						)
						(arc
							(start 0.2794 -0.1778)
							(mid 0.249642 -0.249642)
							(end 0.1778 -0.2794)
						)
					)
					(width 0)
					(fill yes)
				)
			)
		)
	)
	(footprint ""
		(layer "F.Cu")
		(at 58.293 -18.542 90)
		(property "Reference" "R96"
			(at 0 0 90)
			(layer "F.SilkS")
			(hide yes)
			(effects
				(font
					(size 1.27 1.27)
				)
			)
		)
		(property "Value" "100KR2F-L1-GP"
			(at 0.064008 -3.993896 90)
			(unlocked yes)
			(layer "F.Fab")
			(hide yes)
			(effects
				(font
					(size 1.016 1.016)
					(thickness 0.1524)
				)
			)
		)
		(property "Device Type" "R402H16"
			(at 0.064008 -5.517896 90)
			(unlocked yes)
			(layer "F.Fab")
			(hide yes)
			(effects
				(font
					(size 1.016 1.016)
					(thickness 0.1524)
				)
			)
		)
		(duplicate_pad_numbers_are_jumpers no)
		(fp_line
			(start 0.508 -0.9398)
			(end -0.508 -0.9398)
			(stroke
				(width 0.1524)
				(type default)
			)
			(layer "F.SilkS")
		)
		(fp_line
			(start -0.508 -0.9398)
			(end -0.508 0.9398)
			(stroke
				(width 0.1524)
				(type default)
			)
			(layer "F.SilkS")
		)
		(fp_rect
			(start -0.508 0.9398)
			(end 0.508 -0.9398)
			(stroke
				(width 0)
				(type default)
			)
			(fill no)
			(layer "F.CrtYd")
		)
		(fp_rect
			(start -0.508 0.9398)
			(end 0.508 -0.9398)
			(stroke
				(width 0)
				(type default)
			)
			(fill no)
			(layer "F.Fab")
		)
		(pad "1" smd custom
			(at 0 -0.4445 90)
			(size 0.1397 0.1397)
			(layers "F.Cu" "F.Mask" "F.Paste")
			(net "SCC_STBY_PWR_EN")
			(options
				(clearance outline)
				(anchor circle)
			)
			(primitives
				(gr_poly
					(pts
						(arc
							(start -0.1778 -0.2794)
							(mid -0.249642 -0.249642)
							(end -0.2794 -0.1778)
						)
						(arc
							(start -0.2794 0.1778)
							(mid -0.249642 0.249642)
							(end -0.1778 0.2794)
						)
						(arc
							(start 0.1778 0.2794)
							(mid 0.249642 0.249642)
							(end 0.2794 0.1778)
						)
						(arc
							(start 0.2794 -0.1778)
							(mid 0.249642 -0.249642)
							(end 0.1778 -0.2794)
						)
					)
					(width 0)
					(fill yes)
				)
			)
		)
		(pad "2" smd custom
			(at 0 0.4445 90)
			(size 0.1397 0.1397)
			(layers "F.Cu" "F.Mask" "F.Paste")
			(net "GND")
			(options
				(clearance outline)
				(anchor circle)
			)
			(primitives
				(gr_poly
					(pts
						(arc
							(start -0.1778 -0.2794)
							(mid -0.249642 -0.249642)
							(end -0.2794 -0.1778)
						)
						(arc
							(start -0.2794 0.1778)
							(mid -0.249642 0.249642)
							(end -0.1778 0.2794)
						)
						(arc
							(start 0.1778 0.2794)
							(mid 0.249642 0.249642)
							(end 0.2794 0.1778)
						)
						(arc
							(start 0.2794 -0.1778)
							(mid 0.249642 -0.249642)
							(end 0.1778 -0.2794)
						)
					)
					(width 0)
					(fill yes)
				)
			)
		)
	)
	(footprint ""
		(layer "F.Cu")
		(at 51.535076 -53.33619 -90)
		(property "Reference" "C618"
			(at 0 0 270)
			(layer "F.SilkS")
			(hide yes)
			(effects
				(font
					(size 1.27 1.27)
				)
			)
		)
		(property "Value" "SC1KP50V2KX-1GP"
			(at 1.1811 -2.7051 270)
			(unlocked yes)
			(layer "F.Fab")
			(hide yes)
			(effects
				(font
					(size 1.016 1.016)
					(thickness 0.1524)
				)
			)
		)
		(property "Device Type" "C402H22"
			(at 1.1811 -4.2291 270)
			(unlocked yes)
			(layer "F.Fab")
			(hide yes)
			(effects
				(font
					(size 1.016 1.016)
					(thickness 0.1524)
				)
			)
		)
		(duplicate_pad_numbers_are_jumpers no)
		(fp_rect
			(start -0.4318 0.9525)
			(end 0.4318 -0.9525)
			(stroke
				(width 0)
				(type default)
			)
			(fill no)
			(layer "F.CrtYd")
		)
		(fp_rect
			(start -0.4318 0.9525)
			(end 0.4318 -0.9525)
			(stroke
				(width 0)
				(type default)
			)
			(fill no)
			(layer "F.Fab")
		)
		(pad "1" smd custom
			(at 0 -0.4445 270)
			(size 0.1524 0.1524)
			(layers "F.Cu" "F.Mask" "F.Paste")
			(net "P0V9_SNB")
			(options
				(clearance outline)
				(anchor circle)
			)
			(primitives
				(gr_poly
					(pts
						(arc
							(start 0.3048 -0.2032)
							(mid 0.275042 -0.275042)
							(end 0.2032 -0.3048)
						)
						(arc
							(start -0.2032 -0.3048)
							(mid -0.275042 -0.275042)
							(end -0.3048 -0.2032)
						)
						(arc
							(start -0.3048 0.2032)
							(mid -0.275042 0.275042)
							(end -0.2032 0.3048)
						)
						(arc
							(start 0.2032 0.3048)
							(mid 0.275042 0.275042)
							(end 0.3048 0.2032)
						)
					)
					(width 0)
					(fill yes)
				)
			)
		)
		(pad "2" smd custom
			(at 0 0.4445 270)
			(size 0.1524 0.1524)
			(layers "F.Cu" "F.Mask" "F.Paste")
			(net "GND")
			(options
				(clearance outline)
				(anchor circle)
			)
			(primitives
				(gr_poly
					(pts
						(arc
							(start 0.3048 -0.2032)
							(mid 0.275042 -0.275042)
							(end 0.2032 -0.3048)
						)
						(arc
							(start -0.2032 -0.3048)
							(mid -0.275042 -0.275042)
							(end -0.3048 -0.2032)
						)
						(arc
							(start -0.3048 0.2032)
							(mid -0.275042 0.275042)
							(end -0.2032 0.3048)
						)
						(arc
							(start 0.2032 0.3048)
							(mid 0.275042 0.275042)
							(end 0.3048 0.2032)
						)
					)
					(width 0)
					(fill yes)
				)
			)
		)
	)
	(footprint ""
		(layer "F.Cu")
		(at 191.85382 -51.2318 90)
		(property "Reference" "R228"
			(at 0 0 90)
			(layer "F.SilkS")
			(hide yes)
			(effects
				(font
					(size 1.27 1.27)
				)
			)
		)
		(property "Value" "10KR2F-2-GP"
			(at 0.064008 -3.993896 90)
			(unlocked yes)
			(layer "F.Fab")
			(hide yes)
			(effects
				(font
					(size 1.016 1.016)
					(thickness 0.1524)
				)
			)
		)
		(property "Device Type" "R402H16"
			(at 0.064008 -5.517896 90)
			(unlocked yes)
			(layer "F.Fab")
			(hide yes)
			(effects
				(font
					(size 1.016 1.016)
					(thickness 0.1524)
				)
			)
		)
		(duplicate_pad_numbers_are_jumpers no)
		(fp_line
			(start 0.508 -0.9398)
			(end -0.508 -0.9398)
			(stroke
				(width 0.1524)
				(type default)
			)
			(layer "F.SilkS")
		)
		(fp_line
			(start -0.508 -0.9398)
			(end -0.508 0.9398)
			(stroke
				(width 0.1524)
				(type default)
			)
			(layer "F.SilkS")
		)
		(fp_rect
			(start -0.508 0.9398)
			(end 0.508 -0.9398)
			(stroke
				(width 0)
				(type default)
			)
			(fill no)
			(layer "F.CrtYd")
		)
		(fp_rect
			(start -0.508 0.9398)
			(end 0.508 -0.9398)
			(stroke
				(width 0)
				(type default)
			)
			(fill no)
			(layer "F.Fab")
		)
		(pad "1" smd custom
			(at 0 -0.4445 90)
			(size 0.1397 0.1397)
			(layers "F.Cu" "F.Mask" "F.Paste")
			(net "XM_ADDR_11")
			(options
				(clearance outline)
				(anchor circle)
			)
			(primitives
				(gr_poly
					(pts
						(arc
							(start -0.1778 -0.2794)
							(mid -0.249642 -0.249642)
							(end -0.2794 -0.1778)
						)
						(arc
							(start -0.2794 0.1778)
							(mid -0.249642 0.249642)
							(end -0.1778 0.2794)
						)
						(arc
							(start 0.1778 0.2794)
							(mid 0.249642 0.249642)
							(end 0.2794 0.1778)
						)
						(arc
							(start 0.2794 -0.1778)
							(mid 0.249642 -0.249642)
							(end 0.1778 -0.2794)
						)
					)
					(width 0)
					(fill yes)
				)
			)
		)
		(pad "2" smd custom
			(at 0 0.4445 90)
			(size 0.1397 0.1397)
			(layers "F.Cu" "F.Mask" "F.Paste")
			(net "GND")
			(options
				(clearance outline)
				(anchor circle)
			)
			(primitives
				(gr_poly
					(pts
						(arc
							(start -0.1778 -0.2794)
							(mid -0.249642 -0.249642)
							(end -0.2794 -0.1778)
						)
						(arc
							(start -0.2794 0.1778)
							(mid -0.249642 0.249642)
							(end -0.1778 0.2794)
						)
						(arc
							(start 0.1778 0.2794)
							(mid 0.249642 0.249642)
							(end 0.2794 0.1778)
						)
						(arc
							(start 0.2794 -0.1778)
							(mid 0.249642 -0.249642)
							(end 0.1778 -0.2794)
						)
					)
					(width 0)
					(fill yes)
				)
			)
		)
	)
	(footprint ""
		(layer "F.Cu")
		(at 59.3344 -80.4926 90)
		(property "Reference" "C549"
			(at 0 0 90)
			(layer "F.SilkS")
			(hide yes)
			(effects
				(font
					(size 1.27 1.27)
				)
			)
		)
		(property "Value" "SCD1U16V2KX-3GP"
			(at 1.1811 -2.7051 90)
			(unlocked yes)
			(layer "F.Fab")
			(hide yes)
			(effects
				(font
					(size 1.016 1.016)
					(thickness 0.1524)
				)
			)
		)
		(property "Device Type" "C402H22"
			(at 1.1811 -4.2291 90)
			(unlocked yes)
			(layer "F.Fab")
			(hide yes)
			(effects
				(font
					(size 1.016 1.016)
					(thickness 0.1524)
				)
			)
		)
		(duplicate_pad_numbers_are_jumpers no)
		(fp_rect
			(start -0.4318 0.9525)
			(end 0.4318 -0.9525)
			(stroke
				(width 0)
				(type default)
			)
			(fill no)
			(layer "F.CrtYd")
		)
		(fp_rect
			(start -0.4318 0.9525)
			(end 0.4318 -0.9525)
			(stroke
				(width 0)
				(type default)
			)
			(fill no)
			(layer "F.Fab")
		)
		(pad "1" smd custom
			(at 0 -0.4445 90)
			(size 0.1524 0.1524)
			(layers "F.Cu" "F.Mask" "F.Paste")
			(net "P1V8_E")
			(options
				(clearance outline)
				(anchor circle)
			)
			(primitives
				(gr_poly
					(pts
						(arc
							(start 0.3048 -0.2032)
							(mid 0.275042 -0.275042)
							(end 0.2032 -0.3048)
						)
						(arc
							(start -0.2032 -0.3048)
							(mid -0.275042 -0.275042)
							(end -0.3048 -0.2032)
						)
						(arc
							(start -0.3048 0.2032)
							(mid -0.275042 0.275042)
							(end -0.2032 0.3048)
						)
						(arc
							(start 0.2032 0.3048)
							(mid 0.275042 0.275042)
							(end 0.3048 0.2032)
						)
					)
					(width 0)
					(fill yes)
				)
			)
		)
		(pad "2" smd custom
			(at 0 0.4445 90)
			(size 0.1524 0.1524)
			(layers "F.Cu" "F.Mask" "F.Paste")
			(net "GND")
			(options
				(clearance outline)
				(anchor circle)
			)
			(primitives
				(gr_poly
					(pts
						(arc
							(start 0.3048 -0.2032)
							(mid 0.275042 -0.275042)
							(end 0.2032 -0.3048)
						)
						(arc
							(start -0.2032 -0.3048)
							(mid -0.275042 -0.275042)
							(end -0.3048 -0.2032)
						)
						(arc
							(start -0.3048 0.2032)
							(mid -0.275042 0.275042)
							(end -0.2032 0.3048)
						)
						(arc
							(start 0.2032 0.3048)
							(mid 0.275042 0.275042)
							(end 0.3048 0.2032)
						)
					)
					(width 0)
					(fill yes)
				)
			)
		)
	)
	(footprint ""
		(layer "F.Cu")
		(at 154.84348 -92.65158 -90)
		(property "Reference" "U20"
			(at 0 0 270)
			(layer "F.SilkS")
			(hide yes)
			(effects
				(font
					(size 1.27 1.27)
				)
			)
		)
		(property "Value" "TXS0102DCUR-1-GP"
			(at 0 -11.1252 270)
			(unlocked yes)
			(layer "F.Fab")
			(hide yes)
			(effects
				(font
					(size 1.016 1.016)
					(thickness 0.1524)
				)
			)
		)
		(property "Device Type" "SSOIC8-4H36"
			(at 0 -12.6492 270)
			(unlocked yes)
			(layer "F.Fab")
			(hide yes)
			(effects
				(font
					(size 1.016 1.016)
					(thickness 0.1524)
				)
			)
		)
		(duplicate_pad_numbers_are_jumpers no)
		(fp_line
			(start -1.2573 2.1844)
			(end -1.2573 -2.1844)
			(stroke
				(width 0.1524)
				(type default)
			)
			(layer "F.SilkS")
		)
		(fp_line
			(start 1.2573 2.1844)
			(end -1.2573 2.1844)
			(stroke
				(width 0.1524)
				(type default)
			)
			(layer "F.SilkS")
		)
		(fp_line
			(start -1.2954 0.4572)
			(end -1.2954 2.159)
			(stroke
				(width 0.4064)
				(type default)
			)
			(layer "F.SilkS")
		)
		(fp_line
			(start -1.2065 0.2667)
			(end -1.27 0.2667)
			(stroke
				(width 0.1524)
				(type default)
			)
			(layer "F.SilkS")
		)
		(fp_line
			(start -0.9017 -0.0381)
			(end -1.2065 0.2667)
			(stroke
				(width 0.1524)
				(type default)
			)
			(layer "F.SilkS")
		)
		(fp_line
			(start -1.2573 -0.3556)
			(end -1.2192 -0.3556)
			(stroke
				(width 0.1524)
				(type default)
			)
			(layer "F.SilkS")
		)
		(fp_line
			(start -1.2192 -0.3556)
			(end -0.9017 -0.0381)
			(stroke
				(width 0.1524)
				(type default)
			)
			(layer "F.SilkS")
		)
		(fp_line
			(start -1.2573 -2.1844)
			(end 1.2573 -2.1844)
			(stroke
				(width 0.1524)
				(type default)
			)
			(layer "F.SilkS")
		)
		(fp_line
			(start 1.2573 -2.1844)
			(end 1.2573 2.1844)
			(stroke
				(width 0.1524)
				(type default)
			)
			(layer "F.SilkS")
		)
		(fp_poly
			(pts
				(xy -1.5113 2.4384) (xy 1.5113 2.4384) (xy 1.5113 -2.4384) (xy -1.5113 -2.4384)
			)
			(stroke
				(width 0)
				(type default)
			)
			(fill no)
			(layer "F.CrtYd")
		)
		(fp_poly
			(pts
				(xy -1.5113 -2.4384) (xy 1.5113 -2.4384) (xy 1.5113 2.4384) (xy -1.5113 2.4384)
			)
			(stroke
				(width 0)
				(type default)
			)
			(fill no)
			(layer "F.Fab")
		)
		(pad "1" smd rect
			(at -0.75057 1.1684 270)
			(size 0.3048 1.524)
			(layers "F.Cu" "F.Mask" "F.Paste")
			(net "EXP_SMART_RX_R")
		)
		(pad "2" smd rect
			(at -0.25019 1.1684 270)
			(size 0.3048 1.524)
			(layers "F.Cu" "F.Mask" "F.Paste")
			(net "GND")
		)
		(pad "3" smd rect
			(at 0.25019 1.1684 270)
			(size 0.3048 1.524)
			(layers "F.Cu" "F.Mask" "F.Paste")
			(net "P1V8_E")
		)
		(pad "4" smd rect
			(at 0.75057 1.1684 270)
			(size 0.3048 1.524)
			(layers "F.Cu" "F.Mask" "F.Paste")
			(net "SAS_SMART_R_RX")
		)
		(pad "5" smd rect
			(at 0.75057 -1.1684 270)
			(size 0.3048 1.524)
			(layers "F.Cu" "F.Mask" "F.Paste")
			(net "SAS_SMART_R_TX")
		)
		(pad "6" smd rect
			(at 0.25019 -1.1684 270)
			(size 0.3048 1.524)
			(layers "F.Cu" "F.Mask" "F.Paste")
			(net "SMART_UART_EN")
		)
		(pad "7" smd rect
			(at -0.25019 -1.1684 270)
			(size 0.3048 1.524)
			(layers "F.Cu" "F.Mask" "F.Paste")
			(net "P3V3")
		)
		(pad "8" smd rect
			(at -0.75057 -1.1684 270)
			(size 0.3048 1.524)
			(layers "F.Cu" "F.Mask" "F.Paste")
			(net "EXP_SMART_TX_R")
		)
	)
	(footprint ""
		(layer "F.Cu")
		(at 187.2234 -24.2824)
		(property "Reference" "TP130"
			(at 0 0 0)
			(layer "F.SilkS")
			(hide yes)
			(effects
				(font
					(size 1.27 1.27)
				)
			)
		)
		(property "Value" "TPAD28-2-GP"
			(at -0.0127 -1.6637 0)
			(unlocked yes)
			(layer "F.Fab")
			(hide yes)
			(effects
				(font
					(size 1.016 1.016)
					(thickness 0.1524)
				)
			)
		)
		(property "Device Type" "TPAD28"
			(at -0.0127 -3.1877 0)
			(unlocked yes)
			(layer "F.Fab")
			(hide yes)
			(effects
				(font
					(size 1.016 1.016)
					(thickness 0.1524)
				)
			)
		)
		(duplicate_pad_numbers_are_jumpers no)
		(fp_poly
			(pts
				(arc
					(start 0.3556 0)
					(mid -0.3556 0)
					(end 0.3556 0)
				)
			)
			(stroke
				(width 0)
				(type default)
			)
			(fill no)
			(layer "F.CrtYd")
		)
		(fp_poly
			(pts
				(arc
					(start 0.6096 0)
					(mid -0.6096 0)
					(end 0.6096 0)
				)
			)
			(stroke
				(width 0)
				(type default)
			)
			(fill no)
			(layer "F.Fab")
		)
		(pad "1" smd circle
			(at 0 0)
			(size 0.7112 0.7112)
			(layers "F.Cu" "F.Mask" "F.Paste")
			(net "SYS_HALT0#")
		)
	)
)
